#ISCELL
  mstr_misc dns *
  *
#ISCELL
  mstr_symbols intel_corp_bpage *
  *
#ISCELL
  mstr_symbols pvddq_ghj *
  page224_i1
#CELL
  mstr_discrete ir354xx *
  page224_i110
#CELL
  mstr_discrete ir354xx *
  page224_i111
#CELL
  mstr_discrete res *
  page224_i112
#ISCELL
  mstr_symbols gnd *
  page224_i113
#CELL
  mstr_discrete res *
  page224_i114
#ISCELL
  mstr_symbols gnd *
  page224_i115
#CELL
  dev_discrete cap_a *
  page224_i117
#ISCELL
  mstr_symbols gnd *
  page224_i118
#ISCELL
  mstr_symbols gnd *
  page224_i120
#CELL
  mstr_discrete cap *
  page224_i122
#ISCELL
  mstr_symbols gnd *
  page224_i123
#CELL
  dev_discrete cap_a *
  page224_i124
#ISCELL
  mstr_symbols gnd *
  page224_i125
#ISCELL
  mstr_symbols gnd *
  page224_i128
#CELL
  mstr_discrete cap *
  page224_i130
#ISCELL
  mstr_symbols gnd *
  page224_i131
#CELL
  mstr_discrete cap *
  page224_i140
#CELL
  mstr_discrete cap *
  page224_i141
#CELL
  mstr_discrete res *
  page224_i144
#CELL
  mstr_discrete res *
  page224_i145
#CELL
  mstr_discrete res *
  page224_i150
#CELL
  mstr_discrete res *
  page224_i151
#CELL
  w_hdl sc1u10v2kx-4-gp *
  page224_i154
#CELL
  w_hdl sc1u10v2kx-4-gp *
  page224_i155
#CELL
  w_hdl 1r3f-gp *
  page224_i156
#CELL
  w_hdl 1r3f-gp *
  page224_i157
#CELL
  w_hdl ind-120nh-30-gp *
  page224_i160
#CELL
  w_hdl ind-120nh-30-gp *
  page224_i161
#ISCELL
  mstr_symbols gnd *
  page224_i19
#ISCELL
  mstr_standard offpage *
  page224_i3
#ISCELL
  mstr_standard offpage *
  page224_i33
#ISCELL
  mstr_symbols gnd *
  page224_i35
#ISCELL
  mstr_standard offpage *
  page224_i4
#CELL
  mstr_discrete cap *
  page224_i44
#CELL
  mstr_discrete cap *
  page224_i45
#CELL
  mstr_discrete cap *
  page224_i46
#CELL
  mstr_discrete cap *
  page224_i47
#CELL
  mstr_discrete cap *
  page224_i48
#CELL
  mstr_discrete cap *
  page224_i50
#CELL
  dev_discrete cap_a *
  page224_i51
#CELL
  mstr_discrete cap *
  page224_i54
#ISCELL
  mstr_standard offpage *
  page224_i58
#CELL
  mstr_discrete cap *
  page224_i6
#ISCELL
  mstr_standard offpage *
  page224_i61
#ISCELL
  mstr_standard offpage *
  page224_i62
#ISCELL
  mstr_standard offpage *
  page224_i63
#ISCELL
  mstr_symbols pvddq_ghj *
  page224_i64
#CELL
  mstr_discrete cap *
  page224_i68
#ISCELL
  mstr_symbols gnd *
  page224_i69
#ISCELL
  mstr_symbols gnd *
  page224_i7
#ISCELL
  mstr_symbols gnd *
  page224_i70
#CELL
  mstr_discrete cap *
  page224_i72
#CELL
  mstr_discrete cap *
  page224_i75
#CELL
  mstr_discrete cap *
  page224_i77
#CELL
  dev_discrete cap_a *
  page224_i78
#CELL
  mstr_discrete cap *
  page224_i79
#CELL
  mstr_discrete cap *
  page224_i80
#CELL
  mstr_discrete cap *
  page224_i81
#ISCELL
  mstr_standard offpage *
  page224_i82
#ISCELL
  mstr_symbols vcc_core *
  page224_i83
#CELL
  mstr_discrete cap *
  page224_i84
#ISCELL
  mstr_symbols gnd *
  page224_i85
#ISCELL
  mstr_symbols p5v_stby *
  page224_i87
#ISCELL
  mstr_symbols p5v_stby *
  page224_i88
#ISCELL
  mstr_symbols vcc_core *
  page224_i89
